# BASEBOARD_FAB2 (Tioga Pass) — schematic netlist excerpt (pin names and nets, part order shuffled) for the footprints in the layout excerpt that follows; sources: Cadence DE-HDL packaged netlist, KiCad conversion of Wiwynn_Tioga_Pass_MB.brd

C8E12  CAP  0.1UF 25V 10% X7R  pkg 0603LF  page 240 : A = VR_P3V3_STBY_PHASE ; B = VR_P3V3_STBY_BOOT_R
C1F22  CAP_A  0.01UF 25V 10% X7R  pkg 0402V  page 77 : A = M_G_VREF ; B = GND
C3A1  CAP_A  47UF 4V 20% X5R  pkg 0603V  page 228 : A = PVDDQ_KLM ; B = GND

(kicad_pcb
	(version 20260206)
	(generator "pcbnew")
	(generator_version "10.0")
	(general
		(thickness 1.6)
		(legacy_teardrops no)
	)
	(paper "A4")
	(title_block
		(title "Wiwynn_Tioga_Pass_MB.brd")
		(comment 1 "Tioga Pass / footprints 2097-2099 of 4770")
	)
	(layers
		(0 "F.Cu" signal "TOP")
		(4 "In1.Cu" signal "L2GND")
		(6 "In2.Cu" signal "L3")
		(8 "In3.Cu" signal "L4GND")
		(10 "In4.Cu" signal "L5")
		(12 "In5.Cu" signal "L6GND")
		(14 "In6.Cu" signal "L7VCC")
		(16 "In7.Cu" signal "L8VCC")
		(18 "In8.Cu" signal "L9GND")
		(20 "In9.Cu" signal "L10")
		(22 "In10.Cu" signal "L11GND")
		(24 "In11.Cu" signal "L12")
		(26 "In12.Cu" signal "L13GND")
		(2 "B.Cu" signal "BOTTOM")
		(9 "F.Adhes" user "F.Adhesive")
		(11 "B.Adhes" user "B.Adhesive")
		(13 "F.Paste" user "Package Geometry/Pastemask Top")
		(15 "B.Paste" user "Package Geometry/Pastemask Bottom")
		(5 "F.SilkS" user "Ref Des/Silkscreen Top")
		(7 "B.SilkS" user "Ref Des/Silkscreen Bottom")
		(1 "F.Mask" user "Board Geometry/Soldermask Top")
		(3 "B.Mask" user "Board Geometry/Soldermask Bottom")
		(17 "Dwgs.User" user "User.Drawings")
		(19 "Cmts.User" user "User.Comments")
		(21 "Eco1.User" user "User.Eco1")
		(23 "Eco2.User" user "User.Eco2")
		(25 "Edge.Cuts" user "Board Geometry/Outline")
		(27 "Margin" user)
		(31 "F.CrtYd" user "Package Geometry/Place Bound Top")
		(29 "B.CrtYd" user "Package Geometry/Place Bound Bottom")
		(35 "F.Fab" user "Ref Des/Assembly Top")
		(33 "B.Fab" user "Ref Des/Assembly Bottom")
	)
	(footprint ""
		(layer "F.Cu")
		(at 30.583378 -22.160992 90)
		(property "Reference" "C1F22"
			(at 0 0 90)
			(layer "F.SilkS")
			(hide yes)
			(effects
				(font
					(size 1.27 1.27)
				)
			)
		)
		(property "Value" ""
			(at 0 0 90)
			(layer "F.Fab")
			(effects
				(font
					(size 1.27 1.27)
				)
			)
		)
		(duplicate_pad_numbers_are_jumpers no)
		(fp_poly
			(pts
				(xy 0.3048 -0.1016) (xy 0.3048 0.9906) (xy -0.3048 0.9906) (xy -0.3048 -0.1016)
			)
			(stroke
				(width 0)
				(type default)
			)
			(fill no)
			(layer "F.CrtYd")
		)
		(fp_line
			(start 0.3048 -0.1016)
			(end -0.3048 -0.1016)
			(stroke
				(width 0.1)
				(type default)
			)
			(layer "F.Fab")
		)
		(fp_line
			(start -0.3048 -0.1016)
			(end -0.3048 0.9906)
			(stroke
				(width 0.1)
				(type default)
			)
			(layer "F.Fab")
		)
		(fp_line
			(start 0.3048 0.9906)
			(end 0.3048 -0.1016)
			(stroke
				(width 0.1)
				(type default)
			)
			(layer "F.Fab")
		)
		(fp_line
			(start -0.3048 0.9906)
			(end 0.3048 0.9906)
			(stroke
				(width 0.1)
				(type default)
			)
			(layer "F.Fab")
		)
		(pad "1" smd rect
			(at 0 0 90)
			(size 0.508 0.508)
			(layers "F.Cu" "F.Mask" "F.Paste")
			(net "M_G_VREF")
		)
		(pad "2" smd rect
			(at 0 0.889 90)
			(size 0.508 0.508)
			(layers "F.Cu" "F.Mask" "F.Paste")
			(net "GND")
		)
		(zone
			(layer "F.Cu")
			(hatch none 0.5)
			(connect_pads
				(clearance 0)
			)
			(min_thickness 0.25)
			(keepout
				(tracks allowed)
				(vias not_allowed)
				(pads allowed)
				(copperpour not_allowed)
				(footprints allowed)
			)
			(placement
				(enabled no)
				(sheetname "")
			)
			(fill
				(thermal_gap 0.5)
				(thermal_bridge_width 0.5)
				(island_removal_mode 0)
			)
			(polygon
				(pts
					(xy 30.837378 -21.906992) (xy 30.837378 -22.414992) (xy 31.218378 -22.414992) (xy 31.218378 -21.906992)
				)
			)
		)
		(zone
			(layer "F.Cu")
			(hatch none 0.5)
			(connect_pads
				(clearance 0)
			)
			(min_thickness 0.25)
			(keepout
				(tracks not_allowed)
				(vias allowed)
				(pads allowed)
				(copperpour not_allowed)
				(footprints allowed)
			)
			(placement
				(enabled no)
				(sheetname "")
			)
			(fill
				(thermal_gap 0.5)
				(thermal_bridge_width 0.5)
				(island_removal_mode 0)
			)
			(polygon
				(pts
					(xy 31.218378 -21.906992) (xy 31.218378 -22.414992) (xy 30.837378 -22.414992) (xy 30.837378 -21.906992)
				)
			)
		)
	)
	(footprint ""
		(layer "F.Cu")
		(at 107.8611 -149.8092 90)
		(property "Reference" "C3A1"
			(at 1.848866 0.752348 90)
			(unlocked yes)
			(layer "F.SilkS")
			(effects
				(font
					(size 1.27 0.9652)
					(thickness 0.1524)
				)
			)
		)
		(property "Value" ""
			(at 0 0 90)
			(layer "F.Fab")
			(effects
				(font
					(size 1.27 1.27)
				)
			)
		)
		(duplicate_pad_numbers_are_jumpers no)
		(fp_rect
			(start -0.500126 1.598422)
			(end 0.500126 -0.201422)
			(stroke
				(width 0)
				(type default)
			)
			(fill no)
			(layer "F.CrtYd")
		)
		(fp_line
			(start 0.500126 -0.201422)
			(end 0.500126 1.598422)
			(stroke
				(width 0.1)
				(type default)
			)
			(layer "F.Fab")
		)
		(fp_line
			(start -0.500126 -0.201422)
			(end 0.500126 -0.201422)
			(stroke
				(width 0.1)
				(type default)
			)
			(layer "F.Fab")
		)
		(fp_line
			(start 0.500126 1.598422)
			(end -0.500126 1.598422)
			(stroke
				(width 0.1)
				(type default)
			)
			(layer "F.Fab")
		)
		(fp_line
			(start -0.500126 1.598422)
			(end -0.500126 -0.201422)
			(stroke
				(width 0.1)
				(type default)
			)
			(layer "F.Fab")
		)
		(pad "1" smd rect
			(at 0 0)
			(size 0.889 0.9906)
			(layers "F.Cu" "F.Mask" "F.Paste")
			(net "PVDDQ_KLM")
		)
		(pad "2" smd rect
			(at 0 1.397)
			(size 0.889 0.9906)
			(layers "F.Cu" "F.Mask" "F.Paste")
			(net "GND")
		)
		(zone
			(layer "F.Cu")
			(hatch none 0.5)
			(connect_pads
				(clearance 0)
			)
			(min_thickness 0.25)
			(keepout
				(tracks not_allowed)
				(vias allowed)
				(pads allowed)
				(copperpour not_allowed)
				(footprints allowed)
			)
			(placement
				(enabled no)
				(sheetname "")
			)
			(fill
				(thermal_gap 0.5)
				(thermal_bridge_width 0.5)
				(island_removal_mode 0)
			)
			(polygon
				(pts
					(xy 108.8136 -149.3139) (xy 108.8136 -150.3045) (xy 108.3056 -150.3045) (xy 108.3056 -149.3139)
				)
			)
		)
		(zone
			(layer "F.Cu")
			(hatch none 0.5)
			(connect_pads
				(clearance 0)
			)
			(min_thickness 0.25)
			(keepout
				(tracks allowed)
				(vias not_allowed)
				(pads allowed)
				(copperpour not_allowed)
				(footprints allowed)
			)
			(placement
				(enabled no)
				(sheetname "")
			)
			(fill
				(thermal_gap 0.5)
				(thermal_bridge_width 0.5)
				(island_removal_mode 0)
			)
			(polygon
				(pts
					(xy 108.8136 -149.3139) (xy 108.8136 -150.3045) (xy 108.3056 -150.3045) (xy 108.3056 -149.3139)
				)
			)
		)
	)
	(footprint ""
		(layer "F.Cu")
		(at 469.3031 -25.18156 180)
		(property "Reference" "C8E12"
			(at 0 0 180)
			(layer "F.SilkS")
			(hide yes)
			(effects
				(font
					(size 1.27 1.27)
				)
			)
		)
		(property "Value" ""
			(at 0 0 180)
			(layer "F.Fab")
			(effects
				(font
					(size 1.27 1.27)
				)
			)
		)
		(duplicate_pad_numbers_are_jumpers no)
		(fp_rect
			(start 0.4953 -0.2032)
			(end -0.4953 1.6002)
			(stroke
				(width 0)
				(type default)
			)
			(fill no)
			(layer "F.CrtYd")
		)
		(fp_line
			(start 0.4953 1.6002)
			(end -0.4953 1.6002)
			(stroke
				(width 0.1)
				(type default)
			)
			(layer "F.Fab")
		)
		(fp_line
			(start 0.4953 -0.2032)
			(end 0.4953 1.6002)
			(stroke
				(width 0.1)
				(type default)
			)
			(layer "F.Fab")
		)
		(fp_line
			(start -0.4953 1.6002)
			(end -0.4953 -0.2032)
			(stroke
				(width 0.1)
				(type default)
			)
			(layer "F.Fab")
		)
		(fp_line
			(start -0.4953 -0.2032)
			(end 0.4953 -0.2032)
			(stroke
				(width 0.1)
				(type default)
			)
			(layer "F.Fab")
		)
		(pad "1" smd rect
			(at 0 0 180)
			(size 0.762 0.889)
			(layers "F.Cu" "F.Mask" "F.Paste")
			(net "VR_P3V3_STBY_PHASE")
		)
		(pad "2" smd rect
			(at 0 1.397 180)
			(size 0.762 0.889)
			(layers "F.Cu" "F.Mask" "F.Paste")
			(net "VR_P3V3_STBY_BOOT_R")
		)
		(zone
			(layer "F.Cu")
			(hatch none 0.5)
			(connect_pads
				(clearance 0)
			)
			(min_thickness 0.25)
			(keepout
				(tracks not_allowed)
				(vias allowed)
				(pads allowed)
				(copperpour not_allowed)
				(footprints allowed)
			)
			(placement
				(enabled no)
				(sheetname "")
			)
			(fill
				(thermal_gap 0.5)
				(thermal_bridge_width 0.5)
				(island_removal_mode 0)
			)
			(polygon
				(pts
					(xy 468.9221 -25.62606) (xy 469.6841 -25.62606) (xy 469.6841 -26.13406) (xy 468.9221 -26.13406)
				)
			)
		)
	)
)
